(kicad_pcb
	(version 20260206)
	(generator "pcbnew")
	(generator_version "10.0")
	(general
		(thickness 1.6)
		(legacy_teardrops no)
	)
	(paper "A4")
	(title_block
		(title "04192023_DAF0TMB3IC0_F0TG_MB_C_brd_V02_OCP.brd")
		(comment 1 "Grand Teton / footprints 7236-7243 of 8354")
	)
	(layers
		(0 "F.Cu" signal "TOP")
		(4 "In1.Cu" signal "GND")
		(6 "In2.Cu" signal "IN1")
		(8 "In3.Cu" signal "GND1")
		(10 "In4.Cu" signal "IN2")
		(12 "In5.Cu" signal "GND2")
		(14 "In6.Cu" signal "IN3")
		(16 "In7.Cu" signal "GND3")
		(18 "In8.Cu" signal "VCC")
		(20 "In9.Cu" signal "VCC1")
		(22 "In10.Cu" signal "GND4")
		(24 "In11.Cu" signal "IN4")
		(26 "In12.Cu" signal "GND5")
		(28 "In13.Cu" signal "IN5")
		(30 "In14.Cu" signal "GND6")
		(32 "In15.Cu" signal "IN6")
		(34 "In16.Cu" signal "GND7")
		(2 "B.Cu" signal "BOTTOM")
		(9 "F.Adhes" user "F.Adhesive")
		(11 "B.Adhes" user "B.Adhesive")
		(13 "F.Paste" user "Package Geometry/Pastemask Top")
		(15 "B.Paste" user "Package Geometry/Pastemask Bottom")
		(5 "F.SilkS" user "Ref Des/Silkscreen Top")
		(7 "B.SilkS" user "Ref Des/Silkscreen Bottom")
		(1 "F.Mask" user "Board Geometry/Soldermask Top")
		(3 "B.Mask" user "Board Geometry/Soldermask Bottom")
		(17 "Dwgs.User" user "User.Drawings")
		(19 "Cmts.User" user "User.Comments")
		(21 "Eco1.User" user "User.Eco1")
		(23 "Eco2.User" user "User.Eco2")
		(25 "Edge.Cuts" user "Board Geometry/Outline")
		(27 "Margin" user)
		(31 "F.CrtYd" user "Package Geometry/Place Bound Top")
		(29 "B.CrtYd" user "Package Geometry/Place Bound Bottom")
		(35 "F.Fab" user "Ref Des/Assembly Top")
		(33 "B.Fab" user "Ref Des/Assembly Bottom")
	)
	(footprint ""
		(layer "B.Cu")
		(at 58.580782 -148.322792 180)
		(property "Reference" "PR403"
			(at 0 0 0)
			(layer "B.SilkS")
			(hide yes)
			(effects
				(font
					(size 1.27 1.27)
				)
				(justify mirror)
			)
		)
		(property "Value" ""
			(at 0 0 0)
			(layer "B.Fab")
			(effects
				(font
					(size 1.27 1.27)
				)
				(justify mirror)
			)
		)
		(duplicate_pad_numbers_are_jumpers no)
		(fp_line
			(start 0.7874 0.4064)
			(end 0.7874 -0.4064)
			(stroke
				(width 0.1524)
				(type default)
			)
			(layer "B.SilkS")
		)
		(fp_line
			(start 0.7874 -0.4064)
			(end -0.7874 -0.4064)
			(stroke
				(width 0.1524)
				(type default)
			)
			(layer "B.SilkS")
		)
		(fp_line
			(start -0.7874 0.4064)
			(end 0.7874 0.4064)
			(stroke
				(width 0.1524)
				(type default)
			)
			(layer "B.SilkS")
		)
		(fp_line
			(start -0.7874 -0.4064)
			(end -0.7874 0.4064)
			(stroke
				(width 0.1524)
				(type default)
			)
			(layer "B.SilkS")
		)
		(fp_line
			(start 0.67945 0.3048)
			(end 0.67945 -0.305054)
			(stroke
				(width 0.1)
				(type default)
			)
			(layer "B.Fab")
		)
		(fp_line
			(start 0.67945 -0.305054)
			(end 0.12065 -0.305054)
			(stroke
				(width 0.1)
				(type default)
			)
			(layer "B.Fab")
		)
		(fp_line
			(start 0.12065 0.3048)
			(end 0.67945 0.3048)
			(stroke
				(width 0.1)
				(type default)
			)
			(layer "B.Fab")
		)
		(fp_line
			(start 0.12065 0.2794)
			(end 0.12065 0.3048)
			(stroke
				(width 0.1)
				(type default)
			)
			(layer "B.Fab")
		)
		(fp_line
			(start 0.12065 -0.2794)
			(end -0.12065 -0.2794)
			(stroke
				(width 0.1)
				(type default)
			)
			(layer "B.Fab")
		)
		(fp_line
			(start 0.12065 -0.305054)
			(end 0.12065 -0.2794)
			(stroke
				(width 0.1)
				(type default)
			)
			(layer "B.Fab")
		)
		(fp_line
			(start -0.120396 0.3048)
			(end -0.120396 0.2794)
			(stroke
				(width 0.1)
				(type default)
			)
			(layer "B.Fab")
		)
		(fp_line
			(start -0.120396 0.2794)
			(end 0.12065 0.2794)
			(stroke
				(width 0.1)
				(type default)
			)
			(layer "B.Fab")
		)
		(fp_line
			(start -0.12065 -0.2794)
			(end -0.12065 -0.3048)
			(stroke
				(width 0.1)
				(type default)
			)
			(layer "B.Fab")
		)
		(fp_line
			(start -0.12065 -0.3048)
			(end -0.67945 -0.3048)
			(stroke
				(width 0.1)
				(type default)
			)
			(layer "B.Fab")
		)
		(fp_line
			(start -0.67945 0.3048)
			(end -0.120396 0.3048)
			(stroke
				(width 0.1)
				(type default)
			)
			(layer "B.Fab")
		)
		(fp_line
			(start -0.67945 -0.3048)
			(end -0.67945 0.3048)
			(stroke
				(width 0.1)
				(type default)
			)
			(layer "B.Fab")
		)
		(pad "1" smd circle
			(at 0.40005 0)
			(size 0 0)
			(layers "B.Cu" "B.Mask" "B.Paste")
			(net "PVDD18_S5_P1")
		)
		(pad "2" smd circle
			(at -0.40005 0)
			(size 0 0)
			(layers "B.Cu" "B.Mask" "B.Paste")
			(net "GND")
		)
	)
	(footprint ""
		(layer "B.Cu")
		(at 349.355156 -340.99373 -90)
		(property "Reference" "PR416"
			(at 0 0 90)
			(layer "B.SilkS")
			(hide yes)
			(effects
				(font
					(size 1.27 1.27)
				)
				(justify mirror)
			)
		)
		(property "Value" ""
			(at 0 0 90)
			(layer "B.Fab")
			(effects
				(font
					(size 1.27 1.27)
				)
				(justify mirror)
			)
		)
		(duplicate_pad_numbers_are_jumpers no)
		(fp_line
			(start -0.7874 0.4064)
			(end 0.7874 0.4064)
			(stroke
				(width 0.1524)
				(type default)
			)
			(layer "B.SilkS")
		)
		(fp_line
			(start 0.7874 0.4064)
			(end 0.7874 -0.4064)
			(stroke
				(width 0.1524)
				(type default)
			)
			(layer "B.SilkS")
		)
		(fp_line
			(start -0.7874 -0.4064)
			(end -0.7874 0.4064)
			(stroke
				(width 0.1524)
				(type default)
			)
			(layer "B.SilkS")
		)
		(fp_line
			(start 0.7874 -0.4064)
			(end -0.7874 -0.4064)
			(stroke
				(width 0.1524)
				(type default)
			)
			(layer "B.SilkS")
		)
		(fp_line
			(start -0.67945 0.3048)
			(end -0.120396 0.3048)
			(stroke
				(width 0.1)
				(type default)
			)
			(layer "B.Fab")
		)
		(fp_line
			(start -0.120396 0.3048)
			(end -0.120396 0.2794)
			(stroke
				(width 0.1)
				(type default)
			)
			(layer "B.Fab")
		)
		(fp_line
			(start 0.12065 0.3048)
			(end 0.67945 0.3048)
			(stroke
				(width 0.1)
				(type default)
			)
			(layer "B.Fab")
		)
		(fp_line
			(start 0.67945 0.3048)
			(end 0.67945 -0.305054)
			(stroke
				(width 0.1)
				(type default)
			)
			(layer "B.Fab")
		)
		(fp_line
			(start -0.120396 0.2794)
			(end 0.12065 0.2794)
			(stroke
				(width 0.1)
				(type default)
			)
			(layer "B.Fab")
		)
		(fp_line
			(start 0.12065 0.2794)
			(end 0.12065 0.3048)
			(stroke
				(width 0.1)
				(type default)
			)
			(layer "B.Fab")
		)
		(fp_line
			(start -0.12065 -0.2794)
			(end -0.12065 -0.3048)
			(stroke
				(width 0.1)
				(type default)
			)
			(layer "B.Fab")
		)
		(fp_line
			(start 0.12065 -0.2794)
			(end -0.12065 -0.2794)
			(stroke
				(width 0.1)
				(type default)
			)
			(layer "B.Fab")
		)
		(fp_line
			(start -0.67945 -0.3048)
			(end -0.67945 0.3048)
			(stroke
				(width 0.1)
				(type default)
			)
			(layer "B.Fab")
		)
		(fp_line
			(start -0.12065 -0.3048)
			(end -0.67945 -0.3048)
			(stroke
				(width 0.1)
				(type default)
			)
			(layer "B.Fab")
		)
		(fp_line
			(start 0.12065 -0.305054)
			(end 0.12065 -0.2794)
			(stroke
				(width 0.1)
				(type default)
			)
			(layer "B.Fab")
		)
		(fp_line
			(start 0.67945 -0.305054)
			(end 0.12065 -0.305054)
			(stroke
				(width 0.1)
				(type default)
			)
			(layer "B.Fab")
		)
		(pad "1" smd circle
			(at 0.40005 0 90)
			(size 0 0)
			(layers "B.Cu" "B.Mask" "B.Paste")
			(net "PVDDCR_CPU1_P0_PVCC")
		)
		(pad "2" smd circle
			(at -0.40005 0 90)
			(size 0 0)
			(layers "B.Cu" "B.Mask" "B.Paste")
			(net "PVDDCR_CPU1_P0_VCC6")
		)
	)
	(footprint ""
		(layer "B.Cu")
		(at 406.746202 -396.393162 -90)
		(property "Reference" "C985"
			(at 0 0 90)
			(layer "B.SilkS")
			(hide yes)
			(effects
				(font
					(size 1.27 1.27)
				)
				(justify mirror)
			)
		)
		(property "Value" ""
			(at 0 0 90)
			(layer "B.Fab")
			(effects
				(font
					(size 1.27 1.27)
				)
				(justify mirror)
			)
		)
		(duplicate_pad_numbers_are_jumpers no)
		(fp_line
			(start -0.299974 0.150114)
			(end 0.299974 0.150114)
			(stroke
				(width 0.1)
				(type default)
			)
			(layer "B.Fab")
		)
		(fp_line
			(start 0.299974 0.150114)
			(end 0.299974 -0.150114)
			(stroke
				(width 0.1)
				(type default)
			)
			(layer "B.Fab")
		)
		(fp_line
			(start -0.299974 -0.150114)
			(end -0.299974 0.150114)
			(stroke
				(width 0.1)
				(type default)
			)
			(layer "B.Fab")
		)
		(fp_line
			(start 0.299974 -0.150114)
			(end -0.299974 -0.150114)
			(stroke
				(width 0.1)
				(type default)
			)
			(layer "B.Fab")
		)
		(pad "1" smd rect
			(at 0.2667 0 90)
			(size 0.3048 0.381)
			(layers "B.Cu" "B.Mask" "B.Paste")
			(net "P0V9_CPU0_RT2_2A")
		)
		(pad "2" smd rect
			(at -0.2667 0 90)
			(size 0.3048 0.381)
			(layers "B.Cu" "B.Mask" "B.Paste")
			(net "GND")
		)
	)
	(footprint ""
		(layer "B.Cu")
		(at 430.119282 -437.392572 -90)
		(property "Reference" "R4570"
			(at 0 0 90)
			(layer "B.SilkS")
			(hide yes)
			(effects
				(font
					(size 1.27 1.27)
				)
				(justify mirror)
			)
		)
		(property "Value" ""
			(at 0 0 90)
			(layer "B.Fab")
			(effects
				(font
					(size 1.27 1.27)
				)
				(justify mirror)
			)
		)
		(duplicate_pad_numbers_are_jumpers no)
		(fp_line
			(start -0.7874 0.4064)
			(end 0.7874 0.4064)
			(stroke
				(width 0.1524)
				(type default)
			)
			(layer "B.SilkS")
		)
		(fp_line
			(start 0.7874 0.4064)
			(end 0.7874 -0.4064)
			(stroke
				(width 0.1524)
				(type default)
			)
			(layer "B.SilkS")
		)
		(fp_line
			(start -0.7874 -0.4064)
			(end -0.7874 0.4064)
			(stroke
				(width 0.1524)
				(type default)
			)
			(layer "B.SilkS")
		)
		(fp_line
			(start 0.7874 -0.4064)
			(end -0.7874 -0.4064)
			(stroke
				(width 0.1524)
				(type default)
			)
			(layer "B.SilkS")
		)
		(fp_line
			(start -0.67945 0.3048)
			(end -0.120396 0.3048)
			(stroke
				(width 0.1)
				(type default)
			)
			(layer "B.Fab")
		)
		(fp_line
			(start -0.120396 0.3048)
			(end -0.120396 0.2794)
			(stroke
				(width 0.1)
				(type default)
			)
			(layer "B.Fab")
		)
		(fp_line
			(start 0.12065 0.3048)
			(end 0.67945 0.3048)
			(stroke
				(width 0.1)
				(type default)
			)
			(layer "B.Fab")
		)
		(fp_line
			(start 0.67945 0.3048)
			(end 0.67945 -0.305054)
			(stroke
				(width 0.1)
				(type default)
			)
			(layer "B.Fab")
		)
		(fp_line
			(start -0.120396 0.2794)
			(end 0.12065 0.2794)
			(stroke
				(width 0.1)
				(type default)
			)
			(layer "B.Fab")
		)
		(fp_line
			(start 0.12065 0.2794)
			(end 0.12065 0.3048)
			(stroke
				(width 0.1)
				(type default)
			)
			(layer "B.Fab")
		)
		(fp_line
			(start -0.12065 -0.2794)
			(end -0.12065 -0.3048)
			(stroke
				(width 0.1)
				(type default)
			)
			(layer "B.Fab")
		)
		(fp_line
			(start 0.12065 -0.2794)
			(end -0.12065 -0.2794)
			(stroke
				(width 0.1)
				(type default)
			)
			(layer "B.Fab")
		)
		(fp_line
			(start -0.67945 -0.3048)
			(end -0.67945 0.3048)
			(stroke
				(width 0.1)
				(type default)
			)
			(layer "B.Fab")
		)
		(fp_line
			(start -0.12065 -0.3048)
			(end -0.67945 -0.3048)
			(stroke
				(width 0.1)
				(type default)
			)
			(layer "B.Fab")
		)
		(fp_line
			(start 0.12065 -0.305054)
			(end 0.12065 -0.2794)
			(stroke
				(width 0.1)
				(type default)
			)
			(layer "B.Fab")
		)
		(fp_line
			(start 0.67945 -0.305054)
			(end 0.12065 -0.305054)
			(stroke
				(width 0.1)
				(type default)
			)
			(layer "B.Fab")
		)
		(pad "1" smd circle
			(at 0.40005 0 90)
			(size 0 0)
			(layers "B.Cu" "B.Mask" "B.Paste")
			(net "GPU_3V3IO_RSVD3")
		)
		(pad "2" smd circle
			(at -0.40005 0 90)
			(size 0 0)
			(layers "B.Cu" "B.Mask" "B.Paste")
			(net "GPU_3V3IO_RSVD3_ISO")
		)
	)
	(footprint ""
		(layer "B.Cu")
		(at 137.153142 -382.8796 180)
		(property "Reference" "R6903"
			(at 0 0 0)
			(layer "B.SilkS")
			(hide yes)
			(effects
				(font
					(size 1.27 1.27)
				)
				(justify mirror)
			)
		)
		(property "Value" ""
			(at 0 0 0)
			(layer "B.Fab")
			(effects
				(font
					(size 1.27 1.27)
				)
				(justify mirror)
			)
		)
		(duplicate_pad_numbers_are_jumpers no)
		(fp_line
			(start 0.32512 0.175006)
			(end 0.32512 -0.175006)
			(stroke
				(width 0.1)
				(type default)
			)
			(layer "B.Fab")
		)
		(fp_line
			(start 0.32512 -0.175006)
			(end -0.32512 -0.175006)
			(stroke
				(width 0.1)
				(type default)
			)
			(layer "B.Fab")
		)
		(fp_line
			(start -0.32512 0.175006)
			(end 0.32512 0.175006)
			(stroke
				(width 0.1)
				(type default)
			)
			(layer "B.Fab")
		)
		(fp_line
			(start -0.32512 -0.175006)
			(end -0.32512 0.175006)
			(stroke
				(width 0.1)
				(type default)
			)
			(layer "B.Fab")
		)
		(pad "1" smd rect
			(at 0.2667 0)
			(size 0.3048 0.381)
			(layers "B.Cu" "B.Mask" "B.Paste")
			(net "NCF_CPU1_P3_GND")
		)
		(pad "2" smd rect
			(at -0.2667 0 180)
			(size 0.3048 0.381)
			(layers "B.Cu" "B.Mask" "B.Paste")
			(net "GND")
		)
	)
	(footprint ""
		(layer "B.Cu")
		(at 241.173 -224.028 90)
		(property "Reference" "C612"
			(at 0 0 90)
			(layer "B.SilkS")
			(hide yes)
			(effects
				(font
					(size 1.27 1.27)
				)
				(justify mirror)
			)
		)
		(property "Value" ""
			(at 0 0 90)
			(layer "B.Fab")
			(effects
				(font
					(size 1.27 1.27)
				)
				(justify mirror)
			)
		)
		(duplicate_pad_numbers_are_jumpers no)
		(fp_line
			(start 0.7874 -0.4064)
			(end -0.7874 -0.4064)
			(stroke
				(width 0.1524)
				(type default)
			)
			(layer "B.SilkS")
		)
		(fp_line
			(start -0.7874 -0.4064)
			(end -0.7874 0.4064)
			(stroke
				(width 0.1524)
				(type default)
			)
			(layer "B.SilkS")
		)
		(fp_line
			(start 0.7874 0.4064)
			(end 0.7874 -0.4064)
			(stroke
				(width 0.1524)
				(type default)
			)
			(layer "B.SilkS")
		)
		(fp_line
			(start -0.7874 0.4064)
			(end 0.7874 0.4064)
			(stroke
				(width 0.1524)
				(type default)
			)
			(layer "B.SilkS")
		)
		(fp_line
			(start 0.67945 -0.305054)
			(end 0.12065 -0.305054)
			(stroke
				(width 0.1)
				(type default)
			)
			(layer "B.Fab")
		)
		(fp_line
			(start 0.12065 -0.305054)
			(end 0.12065 -0.2794)
			(stroke
				(width 0.1)
				(type default)
			)
			(layer "B.Fab")
		)
		(fp_line
			(start -0.12065 -0.3048)
			(end -0.67945 -0.3048)
			(stroke
				(width 0.1)
				(type default)
			)
			(layer "B.Fab")
		)
		(fp_line
			(start -0.67945 -0.3048)
			(end -0.67945 0.3048)
			(stroke
				(width 0.1)
				(type default)
			)
			(layer "B.Fab")
		)
		(fp_line
			(start 0.12065 -0.2794)
			(end -0.12065 -0.2794)
			(stroke
				(width 0.1)
				(type default)
			)
			(layer "B.Fab")
		)
		(fp_line
			(start -0.12065 -0.2794)
			(end -0.12065 -0.3048)
			(stroke
				(width 0.1)
				(type default)
			)
			(layer "B.Fab")
		)
		(fp_line
			(start 0.12065 0.2794)
			(end 0.12065 0.3048)
			(stroke
				(width 0.1)
				(type default)
			)
			(layer "B.Fab")
		)
		(fp_line
			(start -0.120396 0.2794)
			(end 0.12065 0.2794)
			(stroke
				(width 0.1)
				(type default)
			)
			(layer "B.Fab")
		)
		(fp_line
			(start 0.67945 0.3048)
			(end 0.67945 -0.305054)
			(stroke
				(width 0.1)
				(type default)
			)
			(layer "B.Fab")
		)
		(fp_line
			(start 0.12065 0.3048)
			(end 0.67945 0.3048)
			(stroke
				(width 0.1)
				(type default)
			)
			(layer "B.Fab")
		)
		(fp_line
			(start -0.120396 0.3048)
			(end -0.120396 0.2794)
			(stroke
				(width 0.1)
				(type default)
			)
			(layer "B.Fab")
		)
		(fp_line
			(start -0.67945 0.3048)
			(end -0.120396 0.3048)
			(stroke
				(width 0.1)
				(type default)
			)
			(layer "B.Fab")
		)
		(pad "1" smd circle
			(at 0.40005 0 270)
			(size 0 0)
			(layers "B.Cu" "B.Mask" "B.Paste")
			(net "PVDD18_S5_P0")
		)
		(pad "2" smd circle
			(at -0.40005 0 270)
			(size 0 0)
			(layers "B.Cu" "B.Mask" "B.Paste")
			(net "GND")
		)
	)
	(footprint ""
		(layer "B.Cu")
		(at 140.61948 -9.083548 -90)
		(property "Reference" "R3776"
			(at 0 0 90)
			(layer "B.SilkS")
			(hide yes)
			(effects
				(font
					(size 1.27 1.27)
				)
				(justify mirror)
			)
		)
		(property "Value" ""
			(at 0 0 90)
			(layer "B.Fab")
			(effects
				(font
					(size 1.27 1.27)
				)
				(justify mirror)
			)
		)
		(duplicate_pad_numbers_are_jumpers no)
		(fp_line
			(start -0.7874 0.4064)
			(end 0.7874 0.4064)
			(stroke
				(width 0.1524)
				(type default)
			)
			(layer "B.SilkS")
		)
		(fp_line
			(start 0.7874 0.4064)
			(end 0.7874 -0.4064)
			(stroke
				(width 0.1524)
				(type default)
			)
			(layer "B.SilkS")
		)
		(fp_line
			(start -0.7874 -0.4064)
			(end -0.7874 0.4064)
			(stroke
				(width 0.1524)
				(type default)
			)
			(layer "B.SilkS")
		)
		(fp_line
			(start 0.7874 -0.4064)
			(end -0.7874 -0.4064)
			(stroke
				(width 0.1524)
				(type default)
			)
			(layer "B.SilkS")
		)
		(fp_line
			(start -0.67945 0.3048)
			(end -0.120396 0.3048)
			(stroke
				(width 0.1)
				(type default)
			)
			(layer "B.Fab")
		)
		(fp_line
			(start -0.120396 0.3048)
			(end -0.120396 0.2794)
			(stroke
				(width 0.1)
				(type default)
			)
			(layer "B.Fab")
		)
		(fp_line
			(start 0.12065 0.3048)
			(end 0.67945 0.3048)
			(stroke
				(width 0.1)
				(type default)
			)
			(layer "B.Fab")
		)
		(fp_line
			(start 0.67945 0.3048)
			(end 0.67945 -0.305054)
			(stroke
				(width 0.1)
				(type default)
			)
			(layer "B.Fab")
		)
		(fp_line
			(start -0.120396 0.2794)
			(end 0.12065 0.2794)
			(stroke
				(width 0.1)
				(type default)
			)
			(layer "B.Fab")
		)
		(fp_line
			(start 0.12065 0.2794)
			(end 0.12065 0.3048)
			(stroke
				(width 0.1)
				(type default)
			)
			(layer "B.Fab")
		)
		(fp_line
			(start -0.12065 -0.2794)
			(end -0.12065 -0.3048)
			(stroke
				(width 0.1)
				(type default)
			)
			(layer "B.Fab")
		)
		(fp_line
			(start 0.12065 -0.2794)
			(end -0.12065 -0.2794)
			(stroke
				(width 0.1)
				(type default)
			)
			(layer "B.Fab")
		)
		(fp_line
			(start -0.67945 -0.3048)
			(end -0.67945 0.3048)
			(stroke
				(width 0.1)
				(type default)
			)
			(layer "B.Fab")
		)
		(fp_line
			(start -0.12065 -0.3048)
			(end -0.67945 -0.3048)
			(stroke
				(width 0.1)
				(type default)
			)
			(layer "B.Fab")
		)
		(fp_line
			(start 0.12065 -0.305054)
			(end 0.12065 -0.2794)
			(stroke
				(width 0.1)
				(type default)
			)
			(layer "B.Fab")
		)
		(fp_line
			(start 0.67945 -0.305054)
			(end 0.12065 -0.305054)
			(stroke
				(width 0.1)
				(type default)
			)
			(layer "B.Fab")
		)
		(pad "1" smd circle
			(at 0.40005 0 90)
			(size 0 0)
			(layers "B.Cu" "B.Mask" "B.Paste")
			(net "FM_UARTSW_MSB_N")
		)
		(pad "2" smd circle
			(at -0.40005 0 90)
			(size 0 0)
			(layers "B.Cu" "B.Mask" "B.Paste")
			(net "FM_UARTSW_MSB_R")
		)
	)
	(footprint ""
		(layer "B.Cu")
		(at 255.905 -335.13268 180)
		(property "Reference" "R832"
			(at 0 0 0)
			(layer "B.SilkS")
			(hide yes)
			(effects
				(font
					(size 1.27 1.27)
				)
				(justify mirror)
			)
		)
		(property "Value" ""
			(at 0 0 0)
			(layer "B.Fab")
			(effects
				(font
					(size 1.27 1.27)
				)
				(justify mirror)
			)
		)
		(duplicate_pad_numbers_are_jumpers no)
		(fp_line
			(start 0.32512 0.175006)
			(end 0.32512 -0.175006)
			(stroke
				(width 0.1)
				(type default)
			)
			(layer "B.Fab")
		)
		(fp_line
			(start 0.32512 -0.175006)
			(end -0.32512 -0.175006)
			(stroke
				(width 0.1)
				(type default)
			)
			(layer "B.Fab")
		)
		(fp_line
			(start -0.32512 0.175006)
			(end 0.32512 0.175006)
			(stroke
				(width 0.1)
				(type default)
			)
			(layer "B.Fab")
		)
		(fp_line
			(start -0.32512 -0.175006)
			(end -0.32512 0.175006)
			(stroke
				(width 0.1)
				(type default)
			)
			(layer "B.Fab")
		)
		(pad "1" smd rect
			(at 0.2667 0)
			(size 0.3048 0.381)
			(layers "B.Cu" "B.Mask" "B.Paste")
			(net "SMB_RT_CPU0_P2_ROM_MUX_2D_R_SDA")
		)
		(pad "2" smd rect
			(at -0.2667 0 180)
			(size 0.3048 0.381)
			(layers "B.Cu" "B.Mask" "B.Paste")
			(net "SMB_RT_CPU0_P2_ROM_MUX_2D_SDA")
		)
	)
)
